FILE_TYPE = MULTI_PHYS_TABLE;
PART 'CONN3_C95678002'
{========================================================================================}
:PACK_TYPE | MATERIAL | PART_NUMBER     = EnvComp                  | PART_NUMBER  | JEDEC_TYPE            | CLASS | DESCRIPTION                           | HEIGHT     | COMPONENT_TYPE | LEAD_LENGTH | SPEED_URL | Status |RPL| AML | Bus_Unit | Days ;
{========================================================================================}
'THLF'     | 'CONN'   | 'C95678-002'(!) = 'YES;YES;CNC;CNC;ok;VLD' | 'C95678-002' | 'CONN3_C95678002'     | 'IO'  | '1X3'                                 | '0.346 IN' | 'THMT'         | '0.118'     | 'http://speed.intel.com:8081/speed/module/pdm/item/pdm_item_detail_direct.asp?item_cde=C95678-002&item_rev=01&url_param=unused' | 'Unqual' | 'NO' | '1' | 'SMO_BOARDS' | '14' 
'THLF'     | 'EMPTY'  | 'C95678-002'(!) = 'YES;YES;CNC;CNC;ok;VLD' | 'C95678-002' | 'CONN3_C95678002'     | 'IO'  | '1X3'                                 | '0.346 IN' | 'THMT'         | '0.118'     | 'http://speed.intel.com:8081/speed/module/pdm/item/pdm_item_detail_direct.asp?item_cde=C95678-002&item_rev=01&url_param=unused' | 'Unqual' | 'NO' | '1' | 'SMO_BOARDS' | '14' 
'PIP'      | 'CONN'   | 'C95678-002'(!) = ''                       | 'C95678-002' | 'CONN3_C95678002_PIP' | 'IO'  | 'CONN,HDR,1 X 3,PLG,VT,0.1,093ST,KP'  | '0.346 IN' | 'THMT'         | '0.118'     | 'http://speed.intel.com:8081/speed/module/pdm/item/pdm_item_detail_direct.asp?item_cde=C95678-002&item_rev=01&url_param=unused' | '' | '' | '' | '' | '' 
'PIP'      | 'EMPTY'  | 'C95678-002'(!) = ''                       | 'C95678-002' | 'CONN3_C95678002_PIP' | 'IO'  | 'CONN,HDR,1 X 3,PLG,VT,0.1,093ST,KP'  | '0.346 IN' | 'THMT'         | '0.118'     | 'http://speed.intel.com:8081/speed/module/pdm/item/pdm_item_detail_direct.asp?item_cde=C95678-002&item_rev=01&url_param=unused' | '' | '' | '' | '' | '' 
END_PART
END.
